# BASEBOARD_FAB2 (Tioga Pass) — schematic netlist excerpt (pin names and nets, part order shuffled) for the footprints in the layout excerpt that follows; sources: Cadence DE-HDL packaged netlist, KiCad conversion of Wiwynn_Tioga_Pass_MB.brd

T1D16  TEST-PAD-12P-1-GP-U  pkg DISCRET-GB1  page 258
  DP  = L3_85OHM_10INCH_DN
  DN  = L3_85OHM_10INCH_DP
  GND(0)  = GND
  GND(1)  = GND
  GND(2)  = GND
  GND(3)  = GND
  GND(4)  = GND
  GND(5)  = GND
  GND(6)  = GND
  GND(7)  = GND
  GND(8)  = GND
  GND(9)  = GND

C3L24  CAP_A  22.0UF 4V 20% X6S  pkg 0603V  page 132 : A = PVNN_PCH_STBY ; B = GND
C22W18  SC22U16V5MX-4-GP  20%  pkg SMD-BCG5  page 214 : \1\ = VR_FET_SW_P12V_STBY_PVCCIN_CPU0 ; \2\ = GND

(kicad_pcb
	(version 20260206)
	(generator "pcbnew")
	(generator_version "10.0")
	(general
		(thickness 1.6)
		(legacy_teardrops no)
	)
	(paper "A4")
	(title_block
		(title "Wiwynn_Tioga_Pass_MB.brd")
		(comment 1 "Tioga Pass / footprints 4288-4290 of 4770")
	)
	(layers
		(0 "F.Cu" signal "TOP")
		(4 "In1.Cu" signal "L2GND")
		(6 "In2.Cu" signal "L3")
		(8 "In3.Cu" signal "L4GND")
		(10 "In4.Cu" signal "L5")
		(12 "In5.Cu" signal "L6GND")
		(14 "In6.Cu" signal "L7VCC")
		(16 "In7.Cu" signal "L8VCC")
		(18 "In8.Cu" signal "L9GND")
		(20 "In9.Cu" signal "L10")
		(22 "In10.Cu" signal "L11GND")
		(24 "In11.Cu" signal "L12")
		(26 "In12.Cu" signal "L13GND")
		(2 "B.Cu" signal "BOTTOM")
		(9 "F.Adhes" user "F.Adhesive")
		(11 "B.Adhes" user "B.Adhesive")
		(13 "F.Paste" user "Package Geometry/Pastemask Top")
		(15 "B.Paste" user "Package Geometry/Pastemask Bottom")
		(5 "F.SilkS" user "Ref Des/Silkscreen Top")
		(7 "B.SilkS" user "Ref Des/Silkscreen Bottom")
		(1 "F.Mask" user "Board Geometry/Soldermask Top")
		(3 "B.Mask" user "Board Geometry/Soldermask Bottom")
		(17 "Dwgs.User" user "User.Drawings")
		(19 "Cmts.User" user "User.Comments")
		(21 "Eco1.User" user "User.Eco1")
		(23 "Eco2.User" user "User.Eco2")
		(25 "Edge.Cuts" user "Board Geometry/Outline")
		(27 "Margin" user)
		(31 "F.CrtYd" user "Package Geometry/Place Bound Top")
		(29 "B.CrtYd" user "Package Geometry/Place Bound Bottom")
		(35 "F.Fab" user "Ref Des/Assembly Top")
		(33 "B.Fab" user "Ref Des/Assembly Bottom")
	)
	(footprint ""
		(layer "B.Cu")
		(at 308.874414 -164.908992 90)
		(property "Reference" "T1D16"
			(at 0 0 90)
			(layer "B.SilkS")
			(hide yes)
			(effects
				(font
					(size 1.27 1.27)
				)
				(justify mirror)
			)
		)
		(property "Value" "*"
			(at 3.4036 -4.46405 90)
			(unlocked yes)
			(layer "B.Fab")
			(hide yes)
			(effects
				(font
					(size 0.889 0.889)
					(thickness 0.1524)
				)
				(justify mirror)
			)
		)
		(property "Device Type" "TEST-PAD-12P-1-GP-U_DISCRET-GBA"
			(at 3.4036 -5.98805 90)
			(unlocked yes)
			(layer "B.Fab")
			(hide yes)
			(effects
				(font
					(size 0.889 0.889)
					(thickness 0.1524)
				)
				(justify mirror)
			)
		)
		(duplicate_pad_numbers_are_jumpers no)
		(fp_line
			(start 2.3876 -4.826)
			(end -2.3622 -4.826)
			(stroke
				(width 0.1524)
				(type default)
			)
			(layer "B.SilkS")
		)
		(fp_line
			(start -2.3622 -4.826)
			(end -2.3622 3.4798)
			(stroke
				(width 0.1524)
				(type default)
			)
			(layer "B.SilkS")
		)
		(fp_line
			(start 2.3876 3.4798)
			(end 2.3876 -4.826)
			(stroke
				(width 0.1524)
				(type default)
			)
			(layer "B.SilkS")
		)
		(fp_line
			(start -2.3622 3.4798)
			(end 2.3876 3.4798)
			(stroke
				(width 0.1524)
				(type default)
			)
			(layer "B.SilkS")
		)
		(fp_rect
			(start 2.6416 3.7338)
			(end -2.6162 -5.08)
			(stroke
				(width 0)
				(type default)
			)
			(fill no)
			(layer "B.CrtYd")
		)
		(fp_rect
			(start 2.6416 3.7338)
			(end -2.6162 -5.08)
			(stroke
				(width 0)
				(type default)
			)
			(fill no)
			(layer "B.Fab")
		)
		(pad "1" smd circle
			(at -0.496824 -1.301496 270)
			(size 0.6604 0.6604)
			(layers "B.Cu" "B.Mask" "B.Paste")
			(net "L3_85OHM_10INCH_DN")
		)
		(pad "2" smd circle
			(at 0.503936 -1.301496 270)
			(size 0.6604 0.6604)
			(layers "B.Cu" "B.Mask" "B.Paste")
			(net "L3_85OHM_10INCH_DP")
		)
		(pad "3" smd custom
			(at 0.00889 0.370078 270)
			(size 0.74295 0.74295)
			(layers "B.Cu" "B.Mask" "B.Paste")
			(net "GND")
			(options
				(clearance outline)
				(anchor circle)
			)
			(primitives
				(gr_poly
					(pts
						(xy -2.1209 -1.4859) (xy 2.1209 -1.4859) (xy 2.1209 1.4859) (xy 1.08585 1.4859) (xy 1.08585 0.4699)
						(xy -1.08585 0.4699) (xy -1.08585 1.4859) (xy -2.1209 1.4859)
					)
					(width 0)
					(fill yes)
				)
			)
		)
		(pad "4" thru_hole circle
			(at -1.266444 -3.851656 270)
			(size 1.4478 1.4478)
			(drill 1.0414)
			(layers "*.Cu" "*.Mask")
			(remove_unused_layers no)
			(net "GND")
			(clearance 0.1524)
			(thermal_gap 0.1524)
		)
		(pad "5" thru_hole circle
			(at 1.273556 -3.851656 270)
			(size 1.4478 1.4478)
			(drill 1.0414)
			(layers "*.Cu" "*.Mask")
			(remove_unused_layers no)
			(net "GND")
			(clearance 0.1524)
			(thermal_gap 0.1524)
		)
		(pad "6" thru_hole circle
			(at -1.266444 2.498344 270)
			(size 1.4478 1.4478)
			(drill 1.0414)
			(layers "*.Cu" "*.Mask")
			(remove_unused_layers no)
			(net "GND")
			(clearance 0.1524)
			(thermal_gap 0.1524)
		)
		(pad "7" thru_hole circle
			(at 1.273556 2.498344 270)
			(size 1.4478 1.4478)
			(drill 1.0414)
			(layers "*.Cu" "*.Mask")
			(remove_unused_layers no)
			(net "GND")
			(clearance 0.1524)
			(thermal_gap 0.1524)
		)
		(pad "8" thru_hole circle
			(at -1.27 -0.4572 270)
			(size 0.7112 0.7112)
			(drill 0.4064)
			(layers "*.Cu" "*.Mask")
			(remove_unused_layers no)
			(net "GND")
			(clearance 0.1016)
			(thermal_gap 0.1016)
		)
		(pad "9" thru_hole circle
			(at -1.27 0.762 270)
			(size 0.7112 0.7112)
			(drill 0.4064)
			(layers "*.Cu" "*.Mask")
			(remove_unused_layers no)
			(net "GND")
			(clearance 0.1016)
			(thermal_gap 0.1016)
		)
		(pad "10" thru_hole circle
			(at 0.0254 0.762 270)
			(size 0.7112 0.7112)
			(drill 0.4064)
			(layers "*.Cu" "*.Mask")
			(remove_unused_layers no)
			(net "GND")
			(clearance 0.1016)
			(thermal_gap 0.1016)
		)
		(pad "11" thru_hole circle
			(at 1.27 0.762 270)
			(size 0.7112 0.7112)
			(drill 0.4064)
			(layers "*.Cu" "*.Mask")
			(remove_unused_layers no)
			(net "GND")
			(clearance 0.1016)
			(thermal_gap 0.1016)
		)
		(pad "12" thru_hole circle
			(at 1.27 -0.4572 270)
			(size 0.7112 0.7112)
			(drill 0.4064)
			(layers "*.Cu" "*.Mask")
			(remove_unused_layers no)
			(net "GND")
			(clearance 0.1016)
			(thermal_gap 0.1016)
		)
	)
	(footprint ""
		(layer "B.Cu")
		(at 181.5846 -61.03366 180)
		(property "Reference" "C22W18"
			(at 0 0 0)
			(layer "B.SilkS")
			(hide yes)
			(effects
				(font
					(size 1.27 1.27)
				)
				(justify mirror)
			)
		)
		(property "Value" "*"
			(at 0.0762 -6.2357 180)
			(unlocked yes)
			(layer "B.Fab")
			(hide yes)
			(effects
				(font
					(size 1.27 1.016)
					(thickness 0.1524)
				)
				(justify mirror)
			)
		)
		(property "Device Type" "SC22U16V5MX-4-GP_SMD-BCG5-SC22A"
			(at 0.0762 -8.2677 180)
			(unlocked yes)
			(layer "B.Fab")
			(hide yes)
			(effects
				(font
					(size 1.27 1.016)
					(thickness 0.1524)
				)
				(justify mirror)
			)
		)
		(duplicate_pad_numbers_are_jumpers no)
		(fp_line
			(start -0.635 0)
			(end 0.635 0)
			(stroke
				(width 0.508)
				(type default)
			)
			(layer "B.SilkS")
		)
		(fp_rect
			(start 0.9652 1.778)
			(end -0.9652 -1.778)
			(stroke
				(width 0)
				(type default)
			)
			(fill no)
			(layer "B.CrtYd")
		)
		(fp_poly
			(pts
				(xy 0.9652 -1.778) (xy -0.9652 -1.778) (xy -0.9652 1.778) (xy 0.9652 1.778)
			)
			(stroke
				(width 0)
				(type default)
			)
			(fill no)
			(layer "B.Fab")
		)
		(pad "1" smd rect
			(at 0 -0.9652)
			(size 1.397 1.143)
			(layers "B.Cu" "B.Mask" "B.Paste")
			(net "VR_FET_SW_P12V_STBY_PVCCIN_CPU0")
		)
		(pad "2" smd rect
			(at 0 0.9652)
			(size 1.397 1.143)
			(layers "B.Cu" "B.Mask" "B.Paste")
			(net "GND")
		)
	)
	(footprint ""
		(layer "B.Cu")
		(at 384.7084 -137.541)
		(property "Reference" "C3L24"
			(at 0 0 0)
			(layer "B.SilkS")
			(hide yes)
			(effects
				(font
					(size 1.27 1.27)
				)
				(justify mirror)
			)
		)
		(property "Value" ""
			(at 0 0 0)
			(layer "B.Fab")
			(effects
				(font
					(size 1.27 1.27)
				)
				(justify mirror)
			)
		)
		(duplicate_pad_numbers_are_jumpers no)
		(fp_poly
			(pts
				(xy 0.4953 -0.2032) (xy -0.4953 -0.2032) (xy -0.4953 1.6002) (xy 0.4953 1.6002)
			)
			(stroke
				(width 0)
				(type default)
			)
			(fill no)
			(layer "B.CrtYd")
		)
		(fp_line
			(start -0.4953 -0.2032)
			(end -0.4953 1.6002)
			(stroke
				(width 0.1)
				(type default)
			)
			(layer "B.Fab")
		)
		(fp_line
			(start -0.4953 1.6002)
			(end 0.4953 1.6002)
			(stroke
				(width 0.1)
				(type default)
			)
			(layer "B.Fab")
		)
		(fp_line
			(start 0.4953 -0.2032)
			(end -0.4953 -0.2032)
			(stroke
				(width 0.1)
				(type default)
			)
			(layer "B.Fab")
		)
		(fp_line
			(start 0.4953 1.6002)
			(end 0.4953 -0.2032)
			(stroke
				(width 0.1)
				(type default)
			)
			(layer "B.Fab")
		)
		(pad "1" smd rect
			(at 0 0 180)
			(size 0.762 0.889)
			(layers "B.Cu" "B.Mask" "B.Paste")
			(net "PVNN_PCH_STBY")
		)
		(pad "2" smd rect
			(at 0 1.397 180)
			(size 0.762 0.889)
			(layers "B.Cu" "B.Mask" "B.Paste")
			(net "GND")
		)
		(zone
			(layer "B.Cu")
			(hatch none 0.5)
			(connect_pads
				(clearance 0)
			)
			(min_thickness 0.25)
			(keepout
				(tracks not_allowed)
				(vias allowed)
				(pads allowed)
				(copperpour not_allowed)
				(footprints allowed)
			)
			(placement
				(enabled no)
				(sheetname "")
			)
			(fill
				(thermal_gap 0.5)
				(thermal_bridge_width 0.5)
				(island_removal_mode 0)
			)
			(polygon
				(pts
					(xy 385.0894 -137.0965) (xy 384.3274 -137.0965) (xy 384.3274 -136.5885) (xy 385.0894 -136.5885)
				)
			)
		)
	)
)
